#ISCELL
  pure_quanta quanta_title_block_c *
  *
#CELL
  pure_quanta pt5161lrs *
  page405_i1
#ISCELL
  standard tap *
  page405_i10
#ISCELL
  standard tap *
  page405_i11
#ISCELL
  standard tap *
  page405_i12
#ISCELL
  standard tap *
  page405_i13
#ISCELL
  standard tap *
  page405_i14
#ISCELL
  standard tap *
  page405_i15
#ISCELL
  standard tap *
  page405_i16
#ISCELL
  standard tap *
  page405_i17
#ISCELL
  standard offpage *
  page405_i18
#ISCELL
  standard offpage *
  page405_i19
#ISCELL
  standard tap *
  page405_i2
#ISCELL
  standard tap *
  page405_i20
#ISCELL
  standard tap *
  page405_i21
#ISCELL
  standard tap *
  page405_i22
#ISCELL
  standard tap *
  page405_i23
#ISCELL
  standard tap *
  page405_i24
#ISCELL
  standard tap *
  page405_i25
#ISCELL
  standard tap *
  page405_i26
#ISCELL
  standard tap *
  page405_i27
#ISCELL
  standard tap *
  page405_i28
#ISCELL
  standard tap *
  page405_i29
#ISCELL
  standard tap *
  page405_i3
#ISCELL
  standard tap *
  page405_i30
#ISCELL
  standard tap *
  page405_i31
#ISCELL
  standard tap *
  page405_i32
#ISCELL
  standard tap *
  page405_i33
#ISCELL
  standard tap *
  page405_i34
#ISCELL
  standard tap *
  page405_i35
#ISCELL
  standard offpage *
  page405_i36
#ISCELL
  standard offpage *
  page405_i37
#CELL
  pure_quanta pt5161lrs *
  page405_i38
#ISCELL
  standard tap *
  page405_i4
#ISCELL
  standard tap *
  page405_i5
#ISCELL
  standard tap *
  page405_i6
#ISCELL
  standard tap *
  page405_i7
#ISCELL
  standard tap *
  page405_i8
#ISCELL
  standard tap *
  page405_i9
